# S9S_MB_2U (Grand Teton) — schematic netlist excerpt (pin names and nets, part order shuffled) for the footprints in the layout excerpt that follows; sources: Cadence DE-HDL packaged netlist, KiCad conversion of 03242023_DA0F0TMBIJ0_F0T_Motherboard_J_brd_V01_OCP.brd

H29  HOLE  EMPTY  pkg TH  page 311 : \1\ = NC
R3510  Q_RES  54.9K 1% CHIP  pkg 0402LF  page 148 : A = P3V3_AUX ; B = FM_SMB_1_ALERT_GPU_N
PC1223  Q_CAP  680PF 50V 10% X7R  pkg 0402  page 262 : A = P1V05_PCH_AUX_FB ; B = SH_P1V05_PCH_AUX_P

(kicad_pcb
	(version 20260206)
	(generator "pcbnew")
	(generator_version "10.0")
	(general
		(thickness 1.6)
		(legacy_teardrops no)
	)
	(paper "A4")
	(title_block
		(title "03242023_DA0F0TMBIJ0_F0T_Motherboard_J_brd_V01_OCP.brd")
		(comment 1 "Grand Teton / footprints 836-838 of 6105")
	)
	(layers
		(0 "F.Cu" signal "TOP")
		(4 "In1.Cu" signal "GND")
		(6 "In2.Cu" signal "IN1")
		(8 "In3.Cu" signal "GND1")
		(10 "In4.Cu" signal "IN2")
		(12 "In5.Cu" signal "GND2")
		(14 "In6.Cu" signal "IN3")
		(16 "In7.Cu" signal "GND3")
		(18 "In8.Cu" signal "VCC")
		(20 "In9.Cu" signal "VCC1")
		(22 "In10.Cu" signal "GND4")
		(24 "In11.Cu" signal "IN4")
		(26 "In12.Cu" signal "GND5")
		(28 "In13.Cu" signal "IN5")
		(30 "In14.Cu" signal "GND6")
		(32 "In15.Cu" signal "IN6")
		(34 "In16.Cu" signal "GND7")
		(2 "B.Cu" signal "BOTTOM")
		(9 "F.Adhes" user "F.Adhesive")
		(11 "B.Adhes" user "B.Adhesive")
		(13 "F.Paste" user "Package Geometry/Pastemask Top")
		(15 "B.Paste" user "Package Geometry/Pastemask Bottom")
		(5 "F.SilkS" user "Ref Des/Silkscreen Top")
		(7 "B.SilkS" user "Ref Des/Silkscreen Bottom")
		(1 "F.Mask" user "Board Geometry/Soldermask Top")
		(3 "B.Mask" user "Board Geometry/Soldermask Bottom")
		(17 "Dwgs.User" user "User.Drawings")
		(19 "Cmts.User" user "User.Comments")
		(21 "Eco1.User" user "User.Eco1")
		(23 "Eco2.User" user "User.Eco2")
		(25 "Edge.Cuts" user "Board Geometry/Outline")
		(27 "Margin" user)
		(31 "F.CrtYd" user "Package Geometry/Place Bound Top")
		(29 "B.CrtYd" user "Package Geometry/Place Bound Bottom")
		(35 "F.Fab" user "Ref Des/Assembly Top")
		(33 "B.Fab" user "Ref Des/Assembly Bottom")
	)
	(footprint ""
		(layer "F.Cu")
		(at 260.561582 -77.549502)
		(property "Reference" "PC1223"
			(at 0 0 0)
			(layer "F.SilkS")
			(hide yes)
			(effects
				(font
					(size 1.27 1.27)
				)
			)
		)
		(property "Value" ""
			(at 0 0 0)
			(layer "F.Fab")
			(effects
				(font
					(size 1.27 1.27)
				)
			)
		)
		(duplicate_pad_numbers_are_jumpers no)
		(fp_line
			(start -0.7874 -0.4064)
			(end 0.7874 -0.4064)
			(stroke
				(width 0.1524)
				(type default)
			)
			(layer "F.SilkS")
		)
		(fp_line
			(start -0.7874 0.4064)
			(end -0.7874 -0.4064)
			(stroke
				(width 0.1524)
				(type default)
			)
			(layer "F.SilkS")
		)
		(fp_line
			(start 0.7874 -0.4064)
			(end 0.7874 0.4064)
			(stroke
				(width 0.1524)
				(type default)
			)
			(layer "F.SilkS")
		)
		(fp_line
			(start 0.7874 0.4064)
			(end -0.7874 0.4064)
			(stroke
				(width 0.1524)
				(type default)
			)
			(layer "F.SilkS")
		)
		(fp_line
			(start -0.67945 -0.305054)
			(end -0.12065 -0.305054)
			(stroke
				(width 0.1)
				(type default)
			)
			(layer "F.Fab")
		)
		(fp_line
			(start -0.67945 0.3048)
			(end -0.67945 -0.305054)
			(stroke
				(width 0.1)
				(type default)
			)
			(layer "F.Fab")
		)
		(fp_line
			(start -0.12065 -0.305054)
			(end -0.12065 -0.2794)
			(stroke
				(width 0.1)
				(type default)
			)
			(layer "F.Fab")
		)
		(fp_line
			(start -0.12065 -0.2794)
			(end 0.12065 -0.2794)
			(stroke
				(width 0.1)
				(type default)
			)
			(layer "F.Fab")
		)
		(fp_line
			(start -0.12065 0.2794)
			(end -0.12065 0.3048)
			(stroke
				(width 0.1)
				(type default)
			)
			(layer "F.Fab")
		)
		(fp_line
			(start -0.12065 0.3048)
			(end -0.67945 0.3048)
			(stroke
				(width 0.1)
				(type default)
			)
			(layer "F.Fab")
		)
		(fp_line
			(start 0.120396 0.2794)
			(end -0.12065 0.2794)
			(stroke
				(width 0.1)
				(type default)
			)
			(layer "F.Fab")
		)
		(fp_line
			(start 0.120396 0.3048)
			(end 0.120396 0.2794)
			(stroke
				(width 0.1)
				(type default)
			)
			(layer "F.Fab")
		)
		(fp_line
			(start 0.12065 -0.3048)
			(end 0.67945 -0.3048)
			(stroke
				(width 0.1)
				(type default)
			)
			(layer "F.Fab")
		)
		(fp_line
			(start 0.12065 -0.2794)
			(end 0.12065 -0.3048)
			(stroke
				(width 0.1)
				(type default)
			)
			(layer "F.Fab")
		)
		(fp_line
			(start 0.67945 -0.3048)
			(end 0.67945 0.3048)
			(stroke
				(width 0.1)
				(type default)
			)
			(layer "F.Fab")
		)
		(fp_line
			(start 0.67945 0.3048)
			(end 0.120396 0.3048)
			(stroke
				(width 0.1)
				(type default)
			)
			(layer "F.Fab")
		)
		(pad "1" smd circle
			(at -0.40005 0)
			(size 0 0)
			(layers "F.Cu" "F.Mask" "F.Paste")
			(net "P1V05_PCH_AUX_FB")
		)
		(pad "2" smd circle
			(at 0.40005 0)
			(size 0 0)
			(layers "F.Cu" "F.Mask" "F.Paste")
			(net "SH_P1V05_PCH_AUX_P")
		)
	)
	(footprint ""
		(layer "F.Cu")
		(at 460.49692 -127.627888)
		(property "Reference" "H29"
			(at -5.78358 -6.25729 0)
			(unlocked yes)
			(layer "F.SilkS")
			(effects
				(font
					(size 0.7874 0.5842)
					(thickness 0.1524)
				)
				(justify left)
			)
		)
		(property "Value" ""
			(at 0 0 0)
			(layer "F.Fab")
			(effects
				(font
					(size 1.27 1.27)
				)
			)
		)
		(duplicate_pad_numbers_are_jumpers no)
		(fp_circle
			(center 0 0)
			(end 2.4003 0)
			(stroke
				(width 0.1524)
				(type default)
			)
			(fill no)
			(layer "F.SilkS")
		)
		(fp_arc
			(start 5.668518 3.363214)
			(mid -6.590047 -0.148895)
			(end 5.814314 -3.104896)
			(stroke
				(width 0.1524)
				(type default)
			)
			(layer "B.SilkS")
		)
		(fp_circle
			(center 0 0)
			(end 6.5913 0)
			(stroke
				(width 0.1)
				(type default)
			)
			(fill no)
			(layer "B.Fab")
		)
		(fp_circle
			(center 0 0)
			(end 2.4003 0)
			(stroke
				(width 0.1)
				(type default)
			)
			(fill no)
			(layer "F.Fab")
		)
		(pad "" np_thru_hole circle
			(at 0 0)
			(size 3.175 3.175)
			(drill 3.175)
			(layers "*.Cu" "*.Mask")
			(clearance 0.381)
			(thermal_gap 0.381)
		)
		(zone
			(layers "F.Cu" "B.Cu" "In1.Cu" "In2.Cu" "In3.Cu" "In4.Cu" "In5.Cu" "In6.Cu"
				"In7.Cu" "In8.Cu" "In9.Cu" "In10.Cu" "In11.Cu" "In12.Cu" "In13.Cu" "In14.Cu"
				"In15.Cu" "In16.Cu"
			)
			(hatch none 0.5)
			(connect_pads
				(clearance 0)
			)
			(min_thickness 0.25)
			(keepout
				(tracks not_allowed)
				(vias allowed)
				(pads allowed)
				(copperpour not_allowed)
				(footprints allowed)
			)
			(placement
				(enabled no)
				(sheetname "")
			)
			(fill
				(thermal_gap 0.5)
				(thermal_bridge_width 0.5)
				(island_removal_mode 0)
			)
			(polygon
				(pts
					(arc
						(start 462.59242 -127.627888)
						(mid 458.40142 -127.627888)
						(end 462.59242 -127.627888)
					)
				)
			)
		)
	)
	(footprint ""
		(layer "F.Cu")
		(at 116.84508 -400.414998 -90)
		(property "Reference" "R3510"
			(at 0 0 270)
			(layer "F.SilkS")
			(hide yes)
			(effects
				(font
					(size 1.27 1.27)
				)
			)
		)
		(property "Value" ""
			(at 0 0 270)
			(layer "F.Fab")
			(effects
				(font
					(size 1.27 1.27)
				)
			)
		)
		(duplicate_pad_numbers_are_jumpers no)
		(fp_line
			(start -0.7874 0.4064)
			(end -0.7874 -0.4064)
			(stroke
				(width 0.1524)
				(type default)
			)
			(layer "F.SilkS")
		)
		(fp_line
			(start 0.7874 0.4064)
			(end -0.7874 0.4064)
			(stroke
				(width 0.1524)
				(type default)
			)
			(layer "F.SilkS")
		)
		(fp_line
			(start -0.7874 -0.4064)
			(end 0.7874 -0.4064)
			(stroke
				(width 0.1524)
				(type default)
			)
			(layer "F.SilkS")
		)
		(fp_line
			(start 0.7874 -0.4064)
			(end 0.7874 0.4064)
			(stroke
				(width 0.1524)
				(type default)
			)
			(layer "F.SilkS")
		)
		(fp_line
			(start -0.67945 0.3048)
			(end -0.67945 -0.305054)
			(stroke
				(width 0.1)
				(type default)
			)
			(layer "F.Fab")
		)
		(fp_line
			(start -0.12065 0.3048)
			(end -0.67945 0.3048)
			(stroke
				(width 0.1)
				(type default)
			)
			(layer "F.Fab")
		)
		(fp_line
			(start 0.120396 0.3048)
			(end 0.120396 0.2794)
			(stroke
				(width 0.1)
				(type default)
			)
			(layer "F.Fab")
		)
		(fp_line
			(start 0.67945 0.3048)
			(end 0.120396 0.3048)
			(stroke
				(width 0.1)
				(type default)
			)
			(layer "F.Fab")
		)
		(fp_line
			(start -0.12065 0.2794)
			(end -0.12065 0.3048)
			(stroke
				(width 0.1)
				(type default)
			)
			(layer "F.Fab")
		)
		(fp_line
			(start 0.120396 0.2794)
			(end -0.12065 0.2794)
			(stroke
				(width 0.1)
				(type default)
			)
			(layer "F.Fab")
		)
		(fp_line
			(start -0.12065 -0.2794)
			(end 0.12065 -0.2794)
			(stroke
				(width 0.1)
				(type default)
			)
			(layer "F.Fab")
		)
		(fp_line
			(start 0.12065 -0.2794)
			(end 0.12065 -0.3048)
			(stroke
				(width 0.1)
				(type default)
			)
			(layer "F.Fab")
		)
		(fp_line
			(start 0.12065 -0.3048)
			(end 0.67945 -0.3048)
			(stroke
				(width 0.1)
				(type default)
			)
			(layer "F.Fab")
		)
		(fp_line
			(start 0.67945 -0.3048)
			(end 0.67945 0.3048)
			(stroke
				(width 0.1)
				(type default)
			)
			(layer "F.Fab")
		)
		(fp_line
			(start -0.67945 -0.305054)
			(end -0.12065 -0.305054)
			(stroke
				(width 0.1)
				(type default)
			)
			(layer "F.Fab")
		)
		(fp_line
			(start -0.12065 -0.305054)
			(end -0.12065 -0.2794)
			(stroke
				(width 0.1)
				(type default)
			)
			(layer "F.Fab")
		)
		(pad "1" smd circle
			(at -0.40005 0 270)
			(size 0 0)
			(layers "F.Cu" "F.Mask" "F.Paste")
			(net "P3V3_AUX")
		)
		(pad "2" smd circle
			(at 0.40005 0 270)
			(size 0 0)
			(layers "F.Cu" "F.Mask" "F.Paste")
			(net "FM_SMB_1_ALERT_GPU_N")
		)
	)
)
